# T6G (Grand Teton) — schematic netlist excerpt (pin names and nets, part order shuffled) for the footprints in the layout excerpt that follows; sources: Cadence DE-HDL packaged netlist, KiCad conversion of 04192023_DAF0TMB3IC0_F0TG_MB_C_brd_V02_OCP.brd

C6078  Q_CAP  1UF 25V 10% X6S  pkg C0402  page 177 : A = P1V2_AUX ; B = GND
C6668  Q_CAP_DIFFBUS  DIFF BUS_0.22UF 6.3V 20% X6S  pkg C0201  page 330 : \1\ = P5E_CPU1_P1_TX_BUF_C_DN<3> ; \2\ = P5E_CPU1_P1_TX_BUF_DN<3>
R3936  Q_RES  4.7K 1% CHIP  pkg 0402LF  page 262 : A = HSC_VDD ; B = HSC_D_OC

(kicad_pcb
	(version 20260206)
	(generator "pcbnew")
	(generator_version "10.0")
	(general
		(thickness 1.6)
		(legacy_teardrops no)
	)
	(paper "A4")
	(title_block
		(title "04192023_DAF0TMB3IC0_F0TG_MB_C_brd_V02_OCP.brd")
		(comment 1 "Grand Teton / footprints 6690-6692 of 8354")
	)
	(layers
		(0 "F.Cu" signal "TOP")
		(4 "In1.Cu" signal "GND")
		(6 "In2.Cu" signal "IN1")
		(8 "In3.Cu" signal "GND1")
		(10 "In4.Cu" signal "IN2")
		(12 "In5.Cu" signal "GND2")
		(14 "In6.Cu" signal "IN3")
		(16 "In7.Cu" signal "GND3")
		(18 "In8.Cu" signal "VCC")
		(20 "In9.Cu" signal "VCC1")
		(22 "In10.Cu" signal "GND4")
		(24 "In11.Cu" signal "IN4")
		(26 "In12.Cu" signal "GND5")
		(28 "In13.Cu" signal "IN5")
		(30 "In14.Cu" signal "GND6")
		(32 "In15.Cu" signal "IN6")
		(34 "In16.Cu" signal "GND7")
		(2 "B.Cu" signal "BOTTOM")
		(9 "F.Adhes" user "F.Adhesive")
		(11 "B.Adhes" user "B.Adhesive")
		(13 "F.Paste" user "Package Geometry/Pastemask Top")
		(15 "B.Paste" user "Package Geometry/Pastemask Bottom")
		(5 "F.SilkS" user "Ref Des/Silkscreen Top")
		(7 "B.SilkS" user "Ref Des/Silkscreen Bottom")
		(1 "F.Mask" user "Board Geometry/Soldermask Top")
		(3 "B.Mask" user "Board Geometry/Soldermask Bottom")
		(17 "Dwgs.User" user "User.Drawings")
		(19 "Cmts.User" user "User.Comments")
		(21 "Eco1.User" user "User.Eco1")
		(23 "Eco2.User" user "User.Eco2")
		(25 "Edge.Cuts" user "Board Geometry/Outline")
		(27 "Margin" user)
		(31 "F.CrtYd" user "Package Geometry/Place Bound Top")
		(29 "B.CrtYd" user "Package Geometry/Place Bound Bottom")
		(35 "F.Fab" user "Ref Des/Assembly Top")
		(33 "B.Fab" user "Ref Des/Assembly Bottom")
	)
	(footprint ""
		(layer "B.Cu")
		(at 58.490104 -408.517344 90)
		(property "Reference" "C6668"
			(at 0 0 90)
			(layer "B.SilkS")
			(hide yes)
			(effects
				(font
					(size 1.27 1.27)
				)
				(justify mirror)
			)
		)
		(property "Value" ""
			(at 0 0 90)
			(layer "B.Fab")
			(effects
				(font
					(size 1.27 1.27)
				)
				(justify mirror)
			)
		)
		(duplicate_pad_numbers_are_jumpers no)
		(fp_line
			(start 0.299974 -0.150114)
			(end -0.299974 -0.150114)
			(stroke
				(width 0.1)
				(type default)
			)
			(layer "B.Fab")
		)
		(fp_line
			(start -0.299974 -0.150114)
			(end -0.299974 0.150114)
			(stroke
				(width 0.1)
				(type default)
			)
			(layer "B.Fab")
		)
		(fp_line
			(start 0.299974 0.150114)
			(end 0.299974 -0.150114)
			(stroke
				(width 0.1)
				(type default)
			)
			(layer "B.Fab")
		)
		(fp_line
			(start -0.299974 0.150114)
			(end 0.299974 0.150114)
			(stroke
				(width 0.1)
				(type default)
			)
			(layer "B.Fab")
		)
		(pad "1" smd rect
			(at 0.2667 0 270)
			(size 0.3048 0.381)
			(layers "B.Cu" "B.Mask" "B.Paste")
			(net "P5E_CPU1_P1_TX_BUF_C_DN<3>")
		)
		(pad "2" smd rect
			(at -0.2667 0 270)
			(size 0.3048 0.381)
			(layers "B.Cu" "B.Mask" "B.Paste")
			(net "P5E_CPU1_P1_TX_BUF_DN<3>")
		)
	)
	(footprint ""
		(layer "B.Cu")
		(at 129.188972 -41.947592 -90)
		(property "Reference" "C6078"
			(at 0 0 90)
			(layer "B.SilkS")
			(hide yes)
			(effects
				(font
					(size 1.27 1.27)
				)
				(justify mirror)
			)
		)
		(property "Value" ""
			(at 0 0 90)
			(layer "B.Fab")
			(effects
				(font
					(size 1.27 1.27)
				)
				(justify mirror)
			)
		)
		(duplicate_pad_numbers_are_jumpers no)
		(fp_line
			(start -0.7874 0.4064)
			(end 0.7874 0.4064)
			(stroke
				(width 0.1524)
				(type default)
			)
			(layer "B.SilkS")
		)
		(fp_line
			(start 0.7874 0.4064)
			(end 0.7874 -0.4064)
			(stroke
				(width 0.1524)
				(type default)
			)
			(layer "B.SilkS")
		)
		(fp_line
			(start -0.7874 -0.4064)
			(end -0.7874 0.4064)
			(stroke
				(width 0.1524)
				(type default)
			)
			(layer "B.SilkS")
		)
		(fp_line
			(start 0.7874 -0.4064)
			(end -0.7874 -0.4064)
			(stroke
				(width 0.1524)
				(type default)
			)
			(layer "B.SilkS")
		)
		(fp_line
			(start -0.67945 0.3048)
			(end -0.120396 0.3048)
			(stroke
				(width 0.1)
				(type default)
			)
			(layer "B.Fab")
		)
		(fp_line
			(start -0.120396 0.3048)
			(end -0.120396 0.2794)
			(stroke
				(width 0.1)
				(type default)
			)
			(layer "B.Fab")
		)
		(fp_line
			(start 0.12065 0.3048)
			(end 0.67945 0.3048)
			(stroke
				(width 0.1)
				(type default)
			)
			(layer "B.Fab")
		)
		(fp_line
			(start 0.67945 0.3048)
			(end 0.67945 -0.305054)
			(stroke
				(width 0.1)
				(type default)
			)
			(layer "B.Fab")
		)
		(fp_line
			(start -0.120396 0.2794)
			(end 0.12065 0.2794)
			(stroke
				(width 0.1)
				(type default)
			)
			(layer "B.Fab")
		)
		(fp_line
			(start 0.12065 0.2794)
			(end 0.12065 0.3048)
			(stroke
				(width 0.1)
				(type default)
			)
			(layer "B.Fab")
		)
		(fp_line
			(start -0.12065 -0.2794)
			(end -0.12065 -0.3048)
			(stroke
				(width 0.1)
				(type default)
			)
			(layer "B.Fab")
		)
		(fp_line
			(start 0.12065 -0.2794)
			(end -0.12065 -0.2794)
			(stroke
				(width 0.1)
				(type default)
			)
			(layer "B.Fab")
		)
		(fp_line
			(start -0.67945 -0.3048)
			(end -0.67945 0.3048)
			(stroke
				(width 0.1)
				(type default)
			)
			(layer "B.Fab")
		)
		(fp_line
			(start -0.12065 -0.3048)
			(end -0.67945 -0.3048)
			(stroke
				(width 0.1)
				(type default)
			)
			(layer "B.Fab")
		)
		(fp_line
			(start 0.12065 -0.305054)
			(end 0.12065 -0.2794)
			(stroke
				(width 0.1)
				(type default)
			)
			(layer "B.Fab")
		)
		(fp_line
			(start 0.67945 -0.305054)
			(end 0.12065 -0.305054)
			(stroke
				(width 0.1)
				(type default)
			)
			(layer "B.Fab")
		)
		(pad "1" smd circle
			(at 0.40005 0 90)
			(size 0 0)
			(layers "B.Cu" "B.Mask" "B.Paste")
			(net "P1V2_AUX")
		)
		(pad "2" smd circle
			(at -0.40005 0 90)
			(size 0 0)
			(layers "B.Cu" "B.Mask" "B.Paste")
			(net "GND")
		)
	)
	(footprint ""
		(layer "B.Cu")
		(at 191.26454 -400.709892 90)
		(property "Reference" "R3936"
			(at 0 0 90)
			(layer "B.SilkS")
			(hide yes)
			(effects
				(font
					(size 1.27 1.27)
				)
				(justify mirror)
			)
		)
		(property "Value" ""
			(at 0 0 90)
			(layer "B.Fab")
			(effects
				(font
					(size 1.27 1.27)
				)
				(justify mirror)
			)
		)
		(duplicate_pad_numbers_are_jumpers no)
		(fp_line
			(start 0.7874 -0.4064)
			(end -0.7874 -0.4064)
			(stroke
				(width 0.1524)
				(type default)
			)
			(layer "B.SilkS")
		)
		(fp_line
			(start -0.7874 -0.4064)
			(end -0.7874 0.4064)
			(stroke
				(width 0.1524)
				(type default)
			)
			(layer "B.SilkS")
		)
		(fp_line
			(start 0.7874 0.4064)
			(end 0.7874 -0.4064)
			(stroke
				(width 0.1524)
				(type default)
			)
			(layer "B.SilkS")
		)
		(fp_line
			(start -0.7874 0.4064)
			(end 0.7874 0.4064)
			(stroke
				(width 0.1524)
				(type default)
			)
			(layer "B.SilkS")
		)
		(fp_line
			(start 0.67945 -0.305054)
			(end 0.12065 -0.305054)
			(stroke
				(width 0.1)
				(type default)
			)
			(layer "B.Fab")
		)
		(fp_line
			(start 0.12065 -0.305054)
			(end 0.12065 -0.2794)
			(stroke
				(width 0.1)
				(type default)
			)
			(layer "B.Fab")
		)
		(fp_line
			(start -0.12065 -0.3048)
			(end -0.67945 -0.3048)
			(stroke
				(width 0.1)
				(type default)
			)
			(layer "B.Fab")
		)
		(fp_line
			(start -0.67945 -0.3048)
			(end -0.67945 0.3048)
			(stroke
				(width 0.1)
				(type default)
			)
			(layer "B.Fab")
		)
		(fp_line
			(start 0.12065 -0.2794)
			(end -0.12065 -0.2794)
			(stroke
				(width 0.1)
				(type default)
			)
			(layer "B.Fab")
		)
		(fp_line
			(start -0.12065 -0.2794)
			(end -0.12065 -0.3048)
			(stroke
				(width 0.1)
				(type default)
			)
			(layer "B.Fab")
		)
		(fp_line
			(start 0.12065 0.2794)
			(end 0.12065 0.3048)
			(stroke
				(width 0.1)
				(type default)
			)
			(layer "B.Fab")
		)
		(fp_line
			(start -0.120396 0.2794)
			(end 0.12065 0.2794)
			(stroke
				(width 0.1)
				(type default)
			)
			(layer "B.Fab")
		)
		(fp_line
			(start 0.67945 0.3048)
			(end 0.67945 -0.305054)
			(stroke
				(width 0.1)
				(type default)
			)
			(layer "B.Fab")
		)
		(fp_line
			(start 0.12065 0.3048)
			(end 0.67945 0.3048)
			(stroke
				(width 0.1)
				(type default)
			)
			(layer "B.Fab")
		)
		(fp_line
			(start -0.120396 0.3048)
			(end -0.120396 0.2794)
			(stroke
				(width 0.1)
				(type default)
			)
			(layer "B.Fab")
		)
		(fp_line
			(start -0.67945 0.3048)
			(end -0.120396 0.3048)
			(stroke
				(width 0.1)
				(type default)
			)
			(layer "B.Fab")
		)
		(pad "1" smd circle
			(at 0.40005 0 270)
			(size 0 0)
			(layers "B.Cu" "B.Mask" "B.Paste")
			(net "HSC_VDD")
		)
		(pad "2" smd circle
			(at -0.40005 0 270)
			(size 0 0)
			(layers "B.Cu" "B.Mask" "B.Paste")
			(net "HSC_D_OC")
		)
	)
)
